# BASEBOARD_FAB2 (Tioga Pass) — schematic netlist excerpt (pin names and nets, part order shuffled) for the footprints in the layout excerpt that follows; sources: Cadence DE-HDL packaged netlist, KiCad conversion of Wiwynn_Tioga_Pass_MB.brd

R8C12  RES  20.0 1% CHIP  pkg 0402  page 138 : A = SMB_SMLINK0_STBY_LVC3_SCL_R1 ; B = SMB_SMLINK0_STBY_LVC3_SCL
R2N28  RES  10.0K 1% CHIP  pkg 0402  page 136 : A = P3V3_STBY ; B = FM_PASSWORD_CLEAR_N
C1B18  CAP  10UF 16V 10% X6S  pkg 0805  page 198 : A = P12V_FAN ; B = GND

(kicad_pcb
	(version 20260206)
	(generator "pcbnew")
	(generator_version "10.0")
	(general
		(thickness 1.6)
		(legacy_teardrops no)
	)
	(paper "A4")
	(title_block
		(title "Wiwynn_Tioga_Pass_MB.brd")
		(comment 1 "Tioga Pass / footprints 154-156 of 4770")
	)
	(layers
		(0 "F.Cu" signal "TOP")
		(4 "In1.Cu" signal "L2GND")
		(6 "In2.Cu" signal "L3")
		(8 "In3.Cu" signal "L4GND")
		(10 "In4.Cu" signal "L5")
		(12 "In5.Cu" signal "L6GND")
		(14 "In6.Cu" signal "L7VCC")
		(16 "In7.Cu" signal "L8VCC")
		(18 "In8.Cu" signal "L9GND")
		(20 "In9.Cu" signal "L10")
		(22 "In10.Cu" signal "L11GND")
		(24 "In11.Cu" signal "L12")
		(26 "In12.Cu" signal "L13GND")
		(2 "B.Cu" signal "BOTTOM")
		(9 "F.Adhes" user "F.Adhesive")
		(11 "B.Adhes" user "B.Adhesive")
		(13 "F.Paste" user "Package Geometry/Pastemask Top")
		(15 "B.Paste" user "Package Geometry/Pastemask Bottom")
		(5 "F.SilkS" user "Ref Des/Silkscreen Top")
		(7 "B.SilkS" user "Ref Des/Silkscreen Bottom")
		(1 "F.Mask" user "Board Geometry/Soldermask Top")
		(3 "B.Mask" user "Board Geometry/Soldermask Bottom")
		(17 "Dwgs.User" user "User.Drawings")
		(19 "Cmts.User" user "User.Comments")
		(21 "Eco1.User" user "User.Eco1")
		(23 "Eco2.User" user "User.Eco2")
		(25 "Edge.Cuts" user "Board Geometry/Outline")
		(27 "Margin" user)
		(31 "F.CrtYd" user "Package Geometry/Place Bound Top")
		(29 "B.CrtYd" user "Package Geometry/Place Bound Bottom")
		(35 "F.Fab" user "Ref Des/Assembly Top")
		(33 "B.Fab" user "Ref Des/Assembly Bottom")
	)
	(footprint ""
		(layer "F.Cu")
		(at 408.7495 -109.855 -90)
		(property "Reference" "R2N28"
			(at 0 0 270)
			(layer "F.SilkS")
			(hide yes)
			(effects
				(font
					(size 1.27 1.27)
				)
			)
		)
		(property "Value" ""
			(at 0 0 270)
			(layer "F.Fab")
			(effects
				(font
					(size 1.27 1.27)
				)
			)
		)
		(duplicate_pad_numbers_are_jumpers no)
		(fp_poly
			(pts
				(xy -0.2794 -0.1016) (xy 0.2794 -0.1016) (xy 0.2794 0.9906) (xy -0.2794 0.9906)
			)
			(stroke
				(width 0)
				(type default)
			)
			(fill no)
			(layer "F.CrtYd")
		)
		(fp_line
			(start -0.2794 0.9906)
			(end 0.2794 0.9906)
			(stroke
				(width 0.1)
				(type default)
			)
			(layer "F.Fab")
		)
		(fp_line
			(start 0.2794 0.9906)
			(end 0.2794 -0.1016)
			(stroke
				(width 0.1)
				(type default)
			)
			(layer "F.Fab")
		)
		(fp_line
			(start -0.2794 -0.1016)
			(end -0.2794 0.9906)
			(stroke
				(width 0.1)
				(type default)
			)
			(layer "F.Fab")
		)
		(fp_line
			(start 0.2794 -0.1016)
			(end -0.2794 -0.1016)
			(stroke
				(width 0.1)
				(type default)
			)
			(layer "F.Fab")
		)
		(pad "1" smd rect
			(at 0 0 270)
			(size 0.508 0.508)
			(layers "F.Cu" "F.Mask" "F.Paste")
			(net "P3V3_STBY")
		)
		(pad "2" smd rect
			(at 0 0.889 270)
			(size 0.508 0.508)
			(layers "F.Cu" "F.Mask" "F.Paste")
			(net "FM_PASSWORD_CLEAR_N")
		)
		(zone
			(layer "F.Cu")
			(hatch none 0.5)
			(connect_pads
				(clearance 0)
			)
			(min_thickness 0.25)
			(keepout
				(tracks not_allowed)
				(vias allowed)
				(pads allowed)
				(copperpour not_allowed)
				(footprints allowed)
			)
			(placement
				(enabled no)
				(sheetname "")
			)
			(fill
				(thermal_gap 0.5)
				(thermal_bridge_width 0.5)
				(island_removal_mode 0)
			)
			(polygon
				(pts
					(xy 408.1145 -110.109) (xy 408.1145 -109.601) (xy 408.4955 -109.601) (xy 408.4955 -110.109)
				)
			)
		)
		(zone
			(layer "F.Cu")
			(hatch none 0.5)
			(connect_pads
				(clearance 0)
			)
			(min_thickness 0.25)
			(keepout
				(tracks allowed)
				(vias not_allowed)
				(pads allowed)
				(copperpour not_allowed)
				(footprints allowed)
			)
			(placement
				(enabled no)
				(sheetname "")
			)
			(fill
				(thermal_gap 0.5)
				(thermal_bridge_width 0.5)
				(island_removal_mode 0)
			)
			(polygon
				(pts
					(xy 408.4955 -110.109) (xy 408.4955 -109.601) (xy 408.1145 -109.601) (xy 408.1145 -110.109)
				)
			)
		)
	)
	(footprint ""
		(layer "F.Cu")
		(at 407.8605 -108.204 90)
		(property "Reference" "R8C12"
			(at 0 0 90)
			(layer "F.SilkS")
			(hide yes)
			(effects
				(font
					(size 1.27 1.27)
				)
			)
		)
		(property "Value" ""
			(at 0 0 90)
			(layer "F.Fab")
			(effects
				(font
					(size 1.27 1.27)
				)
			)
		)
		(duplicate_pad_numbers_are_jumpers no)
		(fp_poly
			(pts
				(xy -0.2794 -0.1016) (xy 0.2794 -0.1016) (xy 0.2794 0.9906) (xy -0.2794 0.9906)
			)
			(stroke
				(width 0)
				(type default)
			)
			(fill no)
			(layer "F.CrtYd")
		)
		(fp_line
			(start 0.2794 -0.1016)
			(end -0.2794 -0.1016)
			(stroke
				(width 0.1)
				(type default)
			)
			(layer "F.Fab")
		)
		(fp_line
			(start -0.2794 -0.1016)
			(end -0.2794 0.9906)
			(stroke
				(width 0.1)
				(type default)
			)
			(layer "F.Fab")
		)
		(fp_line
			(start 0.2794 0.9906)
			(end 0.2794 -0.1016)
			(stroke
				(width 0.1)
				(type default)
			)
			(layer "F.Fab")
		)
		(fp_line
			(start -0.2794 0.9906)
			(end 0.2794 0.9906)
			(stroke
				(width 0.1)
				(type default)
			)
			(layer "F.Fab")
		)
		(pad "1" smd rect
			(at 0 0 90)
			(size 0.508 0.508)
			(layers "F.Cu" "F.Mask" "F.Paste")
			(net "SMB_SMLINK0_STBY_LVC3_SCL_R1")
		)
		(pad "2" smd rect
			(at 0 0.889 90)
			(size 0.508 0.508)
			(layers "F.Cu" "F.Mask" "F.Paste")
			(net "SMB_SMLINK0_STBY_LVC3_SCL")
		)
		(zone
			(layer "F.Cu")
			(hatch none 0.5)
			(connect_pads
				(clearance 0)
			)
			(min_thickness 0.25)
			(keepout
				(tracks allowed)
				(vias not_allowed)
				(pads allowed)
				(copperpour not_allowed)
				(footprints allowed)
			)
			(placement
				(enabled no)
				(sheetname "")
			)
			(fill
				(thermal_gap 0.5)
				(thermal_bridge_width 0.5)
				(island_removal_mode 0)
			)
			(polygon
				(pts
					(xy 408.1145 -107.95) (xy 408.1145 -108.458) (xy 408.4955 -108.458) (xy 408.4955 -107.95)
				)
			)
		)
		(zone
			(layer "F.Cu")
			(hatch none 0.5)
			(connect_pads
				(clearance 0)
			)
			(min_thickness 0.25)
			(keepout
				(tracks not_allowed)
				(vias allowed)
				(pads allowed)
				(copperpour not_allowed)
				(footprints allowed)
			)
			(placement
				(enabled no)
				(sheetname "")
			)
			(fill
				(thermal_gap 0.5)
				(thermal_bridge_width 0.5)
				(island_removal_mode 0)
			)
			(polygon
				(pts
					(xy 408.4955 -107.95) (xy 408.4955 -108.458) (xy 408.1145 -108.458) (xy 408.1145 -107.95)
				)
			)
		)
	)
	(footprint ""
		(layer "F.Cu")
		(at 7.333234 -112.123728 90)
		(property "Reference" "C1B18"
			(at 1.47828 0.78994 0)
			(unlocked yes)
			(layer "F.SilkS")
			(effects
				(font
					(size 0.4064 0.254)
					(thickness 0.1524)
				)
			)
		)
		(property "Value" ""
			(at 0 0 90)
			(layer "F.Fab")
			(effects
				(font
					(size 1.27 1.27)
				)
			)
		)
		(duplicate_pad_numbers_are_jumpers no)
		(fp_poly
			(pts
				(xy -0.7239 -0.2159) (xy 0.7239 -0.2159) (xy 0.7239 1.9939) (xy -0.7239 1.9939)
			)
			(stroke
				(width 0)
				(type default)
			)
			(fill no)
			(layer "F.CrtYd")
		)
		(fp_line
			(start 0.7239 -0.2159)
			(end -0.7239 -0.2159)
			(stroke
				(width 0.1)
				(type default)
			)
			(layer "F.Fab")
		)
		(fp_line
			(start -0.7239 -0.2159)
			(end -0.7239 1.9939)
			(stroke
				(width 0.1)
				(type default)
			)
			(layer "F.Fab")
		)
		(fp_line
			(start 0.7239 1.9939)
			(end 0.7239 -0.2159)
			(stroke
				(width 0.1)
				(type default)
			)
			(layer "F.Fab")
		)
		(fp_line
			(start -0.7239 1.9939)
			(end 0.7239 1.9939)
			(stroke
				(width 0.1)
				(type default)
			)
			(layer "F.Fab")
		)
		(pad "1" smd rect
			(at 0 0 90)
			(size 1.27 1.016)
			(layers "F.Cu" "F.Mask" "F.Paste")
			(net "P12V_FAN")
		)
		(pad "2" smd rect
			(at 0 1.778 90)
			(size 1.27 1.016)
			(layers "F.Cu" "F.Mask" "F.Paste")
			(net "GND")
		)
		(zone
			(layer "F.Cu")
			(hatch none 0.5)
			(connect_pads
				(clearance 0)
			)
			(min_thickness 0.25)
			(keepout
				(tracks not_allowed)
				(vias allowed)
				(pads allowed)
				(copperpour not_allowed)
				(footprints allowed)
			)
			(placement
				(enabled no)
				(sheetname "")
			)
			(fill
				(thermal_gap 0.5)
				(thermal_bridge_width 0.5)
				(island_removal_mode 0)
			)
			(polygon
				(pts
					(xy 7.841234 -111.488728) (xy 7.841234 -112.758728) (xy 8.603234 -112.758728) (xy 8.603234 -111.488728)
				)
			)
		)
	)
)
